#ISCELL
  mstr_misc dns *
  *
#ISCELL
  pure_quanta quanta_title_block_c *
  *
#ISCELL
  standard offpage *
  page470_i1
#ISCELL
  pure_quanta_power universal_gnd *
  page470_i10
#ISCELL
  pure_quanta_power universal_gnd *
  page470_i11
#CELL
  pure_quanta q_cap *
  page470_i12
#CELL
  pure_quanta q_res *
  page470_i13
#ISCELL
  mstr_symbols universal_power *
  page470_i14
#ISCELL
  pure_quanta_power universal_gnd *
  page470_i15
#CELL
  pure_quanta q_cap *
  page470_i16
#CELL
  pure_quanta q_cap *
  page470_i17
#CELL
  pure_quanta q_cap *
  page470_i18
#ISCELL
  pure_quanta_power universal_gnd *
  page470_i19
#ISCELL
  pure_quanta_power universal_gnd *
  page470_i2
#CELL
  pure_quanta q_res *
  page470_i20
#CELL
  pure_quanta q_res *
  page470_i21
#CELL
  pure_quanta q_cap *
  page470_i22
#CELL
  pure_quanta q_cap *
  page470_i23
#ISCELL
  pure_quanta_power universal_gnd *
  page470_i24
#CELL
  pure_quanta q_cap *
  page470_i25
#ISCELL
  pure_quanta_power universal_gnd *
  page470_i26
#ISCELL
  pure_quanta_power universal_gnd *
  page470_i27
#CELL
  pure_quanta q_res *
  page470_i28
#CELL
  pure_quanta q_res *
  page470_i29
#CELL
  pure_quanta q_cap *
  page470_i3
#ISCELL
  mstr_symbols universal_power *
  page470_i30
#ISCELL
  pure_quanta_power universal_gnd *
  page470_i31
#CELL
  pure_quanta q_res *
  page470_i32
#CELL
  pure_quanta q_cap *
  page470_i33
#CELL
  pure_quanta q_res *
  page470_i34
#CELL
  pure_quanta q_cap *
  page470_i35
#CELL
  pure_quanta q_res *
  page470_i36
#CELL
  pure_quanta q_inductor *
  page470_i37
#CELL
  pure_quanta q_cap *
  page470_i38
#CELL
  pure_quanta q_cap *
  page470_i39
#ISCELL
  pure_quanta_power universal_gnd *
  page470_i4
#ISCELL
  pure_quanta_power universal_gnd *
  page470_i40
#CELL
  pure_quanta q_cap *
  page470_i41
#CELL
  pure_quanta q_cap *
  page470_i42
#ISCELL
  standard offpage *
  page470_i43
#CELL
  pure_quanta q_cap *
  page470_i44
#CELL
  pure_quanta q_cap *
  page470_i45
#CELL
  pure_quanta q_capp *
  page470_i46
#CELL
  pure_quanta q_capp *
  page470_i47
#ISCELL
  pure_quanta_power universal_gnd *
  page470_i48
#CELL
  pure_quanta q_cap *
  page470_i49
#CELL
  pure_quanta q_cap *
  page470_i5
#ISCELL
  pure_quanta_power p1v0 *
  page470_i50
#CELL
  pure_quanta mpq8633bglec838z *
  page470_i51
#CELL
  pure_quanta q_cap *
  page470_i55
#CELL
  pure_quanta q_cap *
  page470_i56
#CELL
  pure_quanta q_cap *
  page470_i57
#CELL
  pure_quanta q_capp *
  page470_i6
#CELL
  pure_quanta q_cap *
  page470_i7
#ISCELL
  mstr_symbols p1v0_aux *
  page470_i8
#CELL
  pure_quanta q_inductor *
  page470_i9
